FILE_TYPE = CONNECTIVITY;
{Allegro Design Entry HDL 17.2-2016 S081 (4005846) 1/11/2022}
"PAGE_NUMBER" = 61;
0"NC";
1"P5E_CPU1_PE3_TX_DP<15:0>";
2"P5E_CPU1_PE3_TX_DN<15:0>";
3"P5E_CPU1_PE3_RX_DP<15:0>";
4"P5E_CPU1_PE3_RX_DN<15:0>";
5"P5E_CPU1_PE2_TX_DP<15:0>";
6"P5E_CPU1_PE2_TX_DN<15:0>";
7"P5E_CPU1_PE2_RX_DP<15:0>";
8"P5E_CPU1_PE2_RX_DN<15:0>";
9"P5E_CPU1_PE2_RX_DN<15>";
10"P5E_CPU1_PE2_RX_DN<14>";
11"P5E_CPU1_PE2_RX_DN<13>";
12"P5E_CPU1_PE2_RX_DN<12>";
13"P5E_CPU1_PE2_RX_DN<11>";
14"P5E_CPU1_PE2_RX_DN<10>";
15"P5E_CPU1_PE2_RX_DN<9>";
16"P5E_CPU1_PE2_RX_DN<8>";
17"P5E_CPU1_PE2_RX_DN<7>";
18"P5E_CPU1_PE2_RX_DN<6>";
19"P5E_CPU1_PE2_RX_DN<5>";
20"P5E_CPU1_PE2_RX_DN<4>";
21"P5E_CPU1_PE2_RX_DN<3>";
22"P5E_CPU1_PE2_RX_DN<2>";
23"P5E_CPU1_PE2_RX_DN<1>";
24"P5E_CPU1_PE2_RX_DN<0>";
25"P5E_CPU1_PE2_RX_DP<15>";
26"P5E_CPU1_PE2_RX_DP<14>";
27"P5E_CPU1_PE2_RX_DP<13>";
28"P5E_CPU1_PE2_RX_DP<12>";
29"P5E_CPU1_PE2_RX_DP<11>";
30"P5E_CPU1_PE2_RX_DP<10>";
31"P5E_CPU1_PE2_RX_DP<9>";
32"P5E_CPU1_PE2_RX_DP<8>";
33"P5E_CPU1_PE2_RX_DP<7>";
34"P5E_CPU1_PE2_RX_DP<6>";
35"P5E_CPU1_PE2_RX_DP<5>";
36"P5E_CPU1_PE2_RX_DP<4>";
37"P5E_CPU1_PE2_RX_DP<3>";
38"P5E_CPU1_PE2_RX_DP<2>";
39"P5E_CPU1_PE2_RX_DP<1>";
40"P5E_CPU1_PE2_RX_DP<0>";
41"P5E_CPU1_PE2_TX_DN<15>";
42"P5E_CPU1_PE2_TX_DN<14>";
43"P5E_CPU1_PE2_TX_DN<13>";
44"P5E_CPU1_PE2_TX_DN<12>";
45"P5E_CPU1_PE2_TX_DN<11>";
46"P5E_CPU1_PE2_TX_DN<10>";
47"P5E_CPU1_PE2_TX_DN<9>";
48"P5E_CPU1_PE2_TX_DN<8>";
49"P5E_CPU1_PE2_TX_DN<7>";
50"P5E_CPU1_PE2_TX_DN<6>";
51"P5E_CPU1_PE2_TX_DN<5>";
52"P5E_CPU1_PE2_TX_DN<4>";
53"P5E_CPU1_PE2_TX_DN<3>";
54"P5E_CPU1_PE2_TX_DN<2>";
55"P5E_CPU1_PE2_TX_DN<1>";
56"P5E_CPU1_PE2_TX_DN<0>";
57"P5E_CPU1_PE2_TX_DP<15>";
58"P5E_CPU1_PE2_TX_DP<14>";
59"P5E_CPU1_PE2_TX_DP<13>";
60"P5E_CPU1_PE2_TX_DP<12>";
61"P5E_CPU1_PE2_TX_DP<11>";
62"P5E_CPU1_PE2_TX_DP<10>";
63"P5E_CPU1_PE2_TX_DP<9>";
64"P5E_CPU1_PE2_TX_DP<8>";
65"P5E_CPU1_PE2_TX_DP<7>";
66"P5E_CPU1_PE2_TX_DP<6>";
67"P5E_CPU1_PE2_TX_DP<5>";
68"P5E_CPU1_PE2_TX_DP<4>";
69"P5E_CPU1_PE2_TX_DP<3>";
70"P5E_CPU1_PE2_TX_DP<2>";
71"P5E_CPU1_PE2_TX_DP<1>";
72"P5E_CPU1_PE2_TX_DP<0>";
73"P5E_CPU1_PE3_RX_DN<15>";
74"P5E_CPU1_PE3_RX_DN<14>";
75"P5E_CPU1_PE3_RX_DN<13>";
76"P5E_CPU1_PE3_RX_DN<12>";
77"P5E_CPU1_PE3_RX_DN<11>";
78"P5E_CPU1_PE3_RX_DN<10>";
79"P5E_CPU1_PE3_RX_DN<9>";
80"P5E_CPU1_PE3_RX_DN<8>";
81"P5E_CPU1_PE3_RX_DN<7>";
82"P5E_CPU1_PE3_RX_DN<6>";
83"P5E_CPU1_PE3_RX_DN<5>";
84"P5E_CPU1_PE3_RX_DN<4>";
85"P5E_CPU1_PE3_RX_DN<3>";
86"P5E_CPU1_PE3_RX_DN<2>";
87"P5E_CPU1_PE3_RX_DN<1>";
88"P5E_CPU1_PE3_RX_DN<0>";
89"P5E_CPU1_PE3_RX_DP<15>";
90"P5E_CPU1_PE3_RX_DP<14>";
91"P5E_CPU1_PE3_RX_DP<13>";
92"P5E_CPU1_PE3_RX_DP<12>";
93"P5E_CPU1_PE3_RX_DP<11>";
94"P5E_CPU1_PE3_RX_DP<10>";
95"P5E_CPU1_PE3_RX_DP<9>";
96"P5E_CPU1_PE3_RX_DP<8>";
97"P5E_CPU1_PE3_RX_DP<7>";
98"P5E_CPU1_PE3_RX_DP<6>";
99"P5E_CPU1_PE3_RX_DP<5>";
100"P5E_CPU1_PE3_RX_DP<4>";
101"P5E_CPU1_PE3_RX_DP<3>";
102"P5E_CPU1_PE3_RX_DP<2>";
103"P5E_CPU1_PE3_RX_DP<1>";
104"P5E_CPU1_PE3_RX_DP<0>";
105"P5E_CPU1_PE3_TX_DN<15>";
106"P5E_CPU1_PE3_TX_DN<14>";
107"P5E_CPU1_PE3_TX_DN<13>";
108"P5E_CPU1_PE3_TX_DN<12>";
109"P5E_CPU1_PE3_TX_DN<11>";
110"P5E_CPU1_PE3_TX_DN<10>";
111"P5E_CPU1_PE3_TX_DN<9>";
112"P5E_CPU1_PE3_TX_DN<8>";
113"P5E_CPU1_PE3_TX_DN<7>";
114"P5E_CPU1_PE3_TX_DN<6>";
115"P5E_CPU1_PE3_TX_DN<5>";
116"P5E_CPU1_PE3_TX_DN<4>";
117"P5E_CPU1_PE3_TX_DN<3>";
118"P5E_CPU1_PE3_TX_DN<2>";
119"P5E_CPU1_PE3_TX_DN<1>";
120"P5E_CPU1_PE3_TX_DN<0>";
121"P5E_CPU1_PE3_TX_DP<15>";
122"P5E_CPU1_PE3_TX_DP<14>";
123"P5E_CPU1_PE3_TX_DP<13>";
124"P5E_CPU1_PE3_TX_DP<12>";
125"P5E_CPU1_PE3_TX_DP<11>";
126"P5E_CPU1_PE3_TX_DP<10>";
127"P5E_CPU1_PE3_TX_DP<9>";
128"P5E_CPU1_PE3_TX_DP<8>";
129"P5E_CPU1_PE3_TX_DP<7>";
130"P5E_CPU1_PE3_TX_DP<6>";
131"P5E_CPU1_PE3_TX_DP<5>";
132"P5E_CPU1_PE3_TX_DP<4>";
133"P5E_CPU1_PE3_TX_DP<3>";
134"P5E_CPU1_PE3_TX_DP<2>";
135"P5E_CPU1_PE3_TX_DP<1>";
136"P5E_CPU1_PE3_TX_DP<0>";
%"TAP"
"1","(-200,-525)","2","standard","I1";
;
CDS_LIB"standard"
BODY_TYPE"PLUMBING"
HDL_TAP"TRUE";
"B \NAC \NWC"4;
"S \NAC"
BN"0"88;
%"TAP"
"1","(-200,-25)","2","standard","I10";
;
CDS_LIB"standard"
BODY_TYPE"PLUMBING"
HDL_TAP"TRUE";
"B \NAC \NWC"4;
"S \NAC"
BN"10"78;
%"TAP"
"1","(3175,1025)","0","standard","I100";
;
CDS_LIB"standard"
BODY_TYPE"PLUMBING"
HDL_TAP"TRUE";
"B \NAC \NWC"1;
"S \NAC"
BN"14"122;
%"TAP"
"1","(3175,925)","0","standard","I101";
;
CDS_LIB"standard"
BODY_TYPE"PLUMBING"
HDL_TAP"TRUE";
"B \NAC \NWC"1;
"S \NAC"
BN"12"124;
%"TAP"
"1","(3175,1075)","0","standard","I102";
;
CDS_LIB"standard"
BODY_TYPE"PLUMBING"
HDL_TAP"TRUE";
"B \NAC \NWC"1;
"S \NAC"
BN"15"121;
%"TAP"
"1","(-200,-125)","2","standard","I11";
;
CDS_LIB"standard"
BODY_TYPE"PLUMBING"
HDL_TAP"TRUE";
"B \NAC \NWC"4;
"S \NAC"
BN"8"80;
%"SOCKET4677_AZIF0045P001C01CS"
"20","(1500,275)","0","pure_quanta","I12";
;
PART_NUMBER"DGA^7000023"
VALUE"SOCKET4677_AZIF0045-P001C01CS"
MATERIAL"IO"
PART_TYPE"SMLF"
$LOCATION"U1"
CDS_LMAN_SYM_OUTLINE"-1050,950,1050,-950"
NEEDS_NO_SIZE"TRUE"
CDS_LIB"pure_quanta"
CDS_LOCATION"U1"
$SEC"20"
CDS_SEC"20";
"PE3_TX_DP0"
$PN"ED87"136;
"PE3_TX_DP1"
$PN"EC86"135;
"PE3_TX_DP2"
$PN"EA86"134;
"PE3_TX_DP3"
$PN"DW86"133;
"PE3_TX_DP4"
$PN"DU86"132;
"PE3_TX_DP5"
$PN"DR86"131;
"PE3_TX_DP6"
$PN"DN86"130;
"PE3_TX_DP7"
$PN"DL86"129;
"PE3_TX_DP8"
$PN"DJ86"128;
"PE3_TX_DP9"
$PN"DG86"127;
"PE3_TX_DP10"
$PN"DE86"126;
"PE3_TX_DP11"
$PN"DC86"125;
"PE3_TX_DP12"
$PN"DA86"124;
"PE3_TX_DP13"
$PN"CW86"123;
"PE3_TX_DP14"
$PN"CU86"122;
"PE3_TX_DP15"
$PN"CR86"121;
"PE3_TX_DN0"
$PN"EE86"120;
"PE3_TX_DN1"
$PN"EB85"119;
"PE3_TX_DN2"
$PN"DY87"118;
"PE3_TX_DN3"
$PN"DV85"117;
"PE3_TX_DN4"
$PN"DT87"116;
"PE3_TX_DN5"
$PN"DP85"115;
"PE3_TX_DN6"
$PN"DM87"114;
"PE3_TX_DN7"
$PN"DK85"113;
"PE3_TX_DN8"
$PN"DH87"112;
"PE3_TX_DN9"
$PN"DF85"111;
"PE3_TX_DN10"
$PN"DD87"110;
"PE3_TX_DN11"
$PN"DB85"109;
"PE3_TX_DN12"
$PN"CY87"108;
"PE3_TX_DN13"
$PN"CV85"107;
"PE3_TX_DN14"
$PN"CT87"106;
"PE3_TX_DN15"
$PN"CP85"105;
"PE3_RX_DP0"
$PN"EJ90"104;
"PE3_RX_DP1"
$PN"EE90"103;
"PE3_RX_DP2"
$PN"EB89"102;
"PE3_RX_DP3"
$PN"EA90"101;
"PE3_RX_DP4"
$PN"DW90"100;
"PE3_RX_DP5"
$PN"DT91"99;
"PE3_RX_DP6"
$PN"DR90"98;
"PE3_RX_DP7"
$PN"DM91"97;
"PE3_RX_DP8"
$PN"DK89"96;
"PE3_RX_DP9"
$PN"DJ90"95;
"PE3_RX_DP10"
$PN"DF89"94;
"PE3_RX_DP11"
$PN"DE90"93;
"PE3_RX_DP12"
$PN"DC90"92;
"PE3_RX_DP13"
$PN"CY91"91;
"PE3_RX_DP14"
$PN"CW90"90;
"PE3_RX_DP15"
$PN"CT91"89;
"PE3_RX_DN0"
$PN"EH89"88;
"PE3_RX_DN1"
$PN"ED91"87;
"PE3_RX_DN2"
$PN"EC90"86;
"PE3_RX_DN3"
$PN"DY91"85;
"PE3_RX_DN4"
$PN"DV89"84;
"PE3_RX_DN5"
$PN"DU90"83;
"PE3_RX_DN6"
$PN"DP89"82;
"PE3_RX_DN7"
$PN"DN90"81;
"PE3_RX_DN8"
$PN"DL90"80;
"PE3_RX_DN9"
$PN"DH91"79;
"PE3_RX_DN10"
$PN"DG90"78;
"PE3_RX_DN11"
$PN"DD91"77;
"PE3_RX_DN12"
$PN"DB89"76;
"PE3_RX_DN13"
$PN"DA90"75;
"PE3_RX_DN14"
$PN"CV89"74;
"PE3_RX_DN15"
$PN"CU90"73;
%"TAP"
"1","(-200,25)","2","standard","I13";
;
CDS_LIB"standard"
BODY_TYPE"PLUMBING"
HDL_TAP"TRUE";
"B \NAC \NWC"4;
"S \NAC"
BN"11"77;
%"TAP"
"1","(-200,75)","2","standard","I16";
;
CDS_LIB"standard"
BODY_TYPE"PLUMBING"
HDL_TAP"TRUE";
"B \NAC \NWC"4;
"S \NAC"
BN"12"76;
%"TAP"
"1","(-200,125)","2","standard","I17";
;
CDS_LIB"standard"
BODY_TYPE"PLUMBING"
HDL_TAP"TRUE";
"B \NAC \NWC"4;
"S \NAC"
BN"13"75;
%"TAP"
"1","(-200,175)","2","standard","I18";
;
CDS_LIB"standard"
BODY_TYPE"PLUMBING"
HDL_TAP"TRUE";
"B \NAC \NWC"4;
"S \NAC"
BN"14"74;
%"TAP"
"1","(-200,225)","2","standard","I19";
;
CDS_LIB"standard"
BODY_TYPE"PLUMBING"
HDL_TAP"TRUE";
"B \NAC \NWC"4;
"S \NAC"
BN"15"73;
%"TAP"
"1","(-200,-475)","2","standard","I2";
;
CDS_LIB"standard"
BODY_TYPE"PLUMBING"
HDL_TAP"TRUE";
"B \NAC \NWC"4;
"S \NAC"
BN"1"87;
%"TAP"
"1","(-200,425)","2","standard","I20";
;
CDS_LIB"standard"
BODY_TYPE"PLUMBING"
HDL_TAP"TRUE";
"B \NAC \NWC"3;
"S \NAC"
BN"2"102;
%"TAP"
"1","(-200,475)","2","standard","I21";
;
CDS_LIB"standard"
BODY_TYPE"PLUMBING"
HDL_TAP"TRUE";
"B \NAC \NWC"3;
"S \NAC"
BN"3"101;
%"TAP"
"1","(-200,375)","2","standard","I22";
;
CDS_LIB"standard"
BODY_TYPE"PLUMBING"
HDL_TAP"TRUE";
"B \NAC \NWC"3;
"S \NAC"
BN"1"103;
%"TAP"
"1","(-175,2300)","2","standard","I225";
;
CDS_LIB"standard"
BODY_TYPE"PLUMBING"
HDL_TAP"TRUE";
"B \NAC \NWC"8;
"S \NAC"
BN"1"23;
%"TAP"
"1","(-175,2250)","2","standard","I226";
;
CDS_LIB"standard"
BODY_TYPE"PLUMBING"
HDL_TAP"TRUE";
"B \NAC \NWC"8;
"S \NAC"
BN"0"24;
%"TAP"
"1","(-175,2350)","2","standard","I227";
;
CDS_LIB"standard"
BODY_TYPE"PLUMBING"
HDL_TAP"TRUE";
"B \NAC \NWC"8;
"S \NAC"
BN"2"22;
%"TAP"
"1","(-175,2450)","2","standard","I228";
;
CDS_LIB"standard"
BODY_TYPE"PLUMBING"
HDL_TAP"TRUE";
"B \NAC \NWC"8;
"S \NAC"
BN"4"20;
%"TAP"
"1","(-175,2400)","2","standard","I229";
;
CDS_LIB"standard"
BODY_TYPE"PLUMBING"
HDL_TAP"TRUE";
"B \NAC \NWC"8;
"S \NAC"
BN"3"21;
%"TAP"
"1","(-200,325)","2","standard","I23";
;
CDS_LIB"standard"
BODY_TYPE"PLUMBING"
HDL_TAP"TRUE";
"B \NAC \NWC"3;
"S \NAC"
BN"0"104;
%"TAP"
"1","(-175,2550)","2","standard","I230";
;
CDS_LIB"standard"
BODY_TYPE"PLUMBING"
HDL_TAP"TRUE";
"B \NAC \NWC"8;
"S \NAC"
BN"6"18;
%"TAP"
"1","(-175,2500)","2","standard","I231";
;
CDS_LIB"standard"
BODY_TYPE"PLUMBING"
HDL_TAP"TRUE";
"B \NAC \NWC"8;
"S \NAC"
BN"5"19;
%"TAP"
"1","(-175,2600)","2","standard","I232";
;
CDS_LIB"standard"
BODY_TYPE"PLUMBING"
HDL_TAP"TRUE";
"B \NAC \NWC"8;
"S \NAC"
BN"7"17;
%"TAP"
"1","(-175,2700)","2","standard","I233";
;
CDS_LIB"standard"
BODY_TYPE"PLUMBING"
HDL_TAP"TRUE";
"B \NAC \NWC"8;
"S \NAC"
BN"9"15;
%"TAP"
"1","(-175,2650)","2","standard","I234";
;
CDS_LIB"standard"
BODY_TYPE"PLUMBING"
HDL_TAP"TRUE";
"B \NAC \NWC"8;
"S \NAC"
BN"8"16;
%"TAP"
"1","(-175,2850)","2","standard","I235";
;
CDS_LIB"standard"
BODY_TYPE"PLUMBING"
HDL_TAP"TRUE";
"B \NAC \NWC"8;
"S \NAC"
BN"12"12;
%"TAP"
"1","(-175,3100)","2","standard","I236";
;
CDS_LIB"standard"
BODY_TYPE"PLUMBING"
HDL_TAP"TRUE";
"B \NAC \NWC"7;
"S \NAC"
BN"0"40;
%"TAP"
"1","(-175,3200)","2","standard","I237";
;
CDS_LIB"standard"
BODY_TYPE"PLUMBING"
HDL_TAP"TRUE";
"B \NAC \NWC"7;
"S \NAC"
BN"2"38;
%"TAP"
"1","(-175,3150)","2","standard","I238";
;
CDS_LIB"standard"
BODY_TYPE"PLUMBING"
HDL_TAP"TRUE";
"B \NAC \NWC"7;
"S \NAC"
BN"1"39;
%"TAP"
"1","(-175,3250)","2","standard","I239";
;
CDS_LIB"standard"
BODY_TYPE"PLUMBING"
HDL_TAP"TRUE";
"B \NAC \NWC"7;
"S \NAC"
BN"3"37;
%"TAP"
"1","(-200,525)","2","standard","I24";
;
CDS_LIB"standard"
BODY_TYPE"PLUMBING"
HDL_TAP"TRUE";
"B \NAC \NWC"3;
"S \NAC"
BN"4"100;
%"TAP"
"1","(-175,3350)","2","standard","I240";
;
CDS_LIB"standard"
BODY_TYPE"PLUMBING"
HDL_TAP"TRUE";
"B \NAC \NWC"7;
"S \NAC"
BN"5"35;
%"TAP"
"1","(-175,3300)","2","standard","I241";
;
CDS_LIB"standard"
BODY_TYPE"PLUMBING"
HDL_TAP"TRUE";
"B \NAC \NWC"7;
"S \NAC"
BN"4"36;
%"TAP"
"1","(-175,3450)","2","standard","I242";
;
CDS_LIB"standard"
BODY_TYPE"PLUMBING"
HDL_TAP"TRUE";
"B \NAC \NWC"7;
"S \NAC"
BN"7"33;
%"TAP"
"1","(-175,3400)","2","standard","I243";
;
CDS_LIB"standard"
BODY_TYPE"PLUMBING"
HDL_TAP"TRUE";
"B \NAC \NWC"7;
"S \NAC"
BN"6"34;
%"TAP"
"1","(-175,3500)","2","standard","I244";
;
CDS_LIB"standard"
BODY_TYPE"PLUMBING"
HDL_TAP"TRUE";
"B \NAC \NWC"7;
"S \NAC"
BN"8"32;
%"TAP"
"1","(-175,3600)","2","standard","I245";
;
CDS_LIB"standard"
BODY_TYPE"PLUMBING"
HDL_TAP"TRUE";
"B \NAC \NWC"7;
"S \NAC"
BN"10"30;
%"TAP"
"1","(-175,3550)","2","standard","I246";
;
CDS_LIB"standard"
BODY_TYPE"PLUMBING"
HDL_TAP"TRUE";
"B \NAC \NWC"7;
"S \NAC"
BN"9"31;
%"TAP"
"1","(-175,3700)","2","standard","I247";
;
CDS_LIB"standard"
BODY_TYPE"PLUMBING"
HDL_TAP"TRUE";
"B \NAC \NWC"7;
"S \NAC"
BN"12"28;
%"TAP"
"1","(-175,3650)","2","standard","I248";
;
CDS_LIB"standard"
BODY_TYPE"PLUMBING"
HDL_TAP"TRUE";
"B \NAC \NWC"7;
"S \NAC"
BN"11"29;
%"TAP"
"1","(-175,3750)","2","standard","I249";
;
CDS_LIB"standard"
BODY_TYPE"PLUMBING"
HDL_TAP"TRUE";
"B \NAC \NWC"7;
"S \NAC"
BN"13"27;
%"TAP"
"1","(-200,575)","2","standard","I25";
;
CDS_LIB"standard"
BODY_TYPE"PLUMBING"
HDL_TAP"TRUE";
"B \NAC \NWC"3;
"S \NAC"
BN"5"99;
%"TAP"
"1","(-175,3850)","2","standard","I250";
;
CDS_LIB"standard"
BODY_TYPE"PLUMBING"
HDL_TAP"TRUE";
"B \NAC \NWC"7;
"S \NAC"
BN"15"25;
%"TAP"
"1","(-175,3800)","2","standard","I251";
;
CDS_LIB"standard"
BODY_TYPE"PLUMBING"
HDL_TAP"TRUE";
"B \NAC \NWC"7;
"S \NAC"
BN"14"26;
%"TAP"
"1","(-175,2750)","2","standard","I252";
;
CDS_LIB"standard"
BODY_TYPE"PLUMBING"
HDL_TAP"TRUE";
"B \NAC \NWC"8;
"S \NAC"
BN"10"14;
%"TAP"
"1","(-175,2800)","2","standard","I253";
;
CDS_LIB"standard"
BODY_TYPE"PLUMBING"
HDL_TAP"TRUE";
"B \NAC \NWC"8;
"S \NAC"
BN"11"13;
%"TAP"
"1","(-175,2900)","2","standard","I254";
;
CDS_LIB"standard"
BODY_TYPE"PLUMBING"
HDL_TAP"TRUE";
"B \NAC \NWC"8;
"S \NAC"
BN"13"11;
%"TAP"
"1","(-175,2950)","2","standard","I255";
;
CDS_LIB"standard"
BODY_TYPE"PLUMBING"
HDL_TAP"TRUE";
"B \NAC \NWC"8;
"S \NAC"
BN"14"10;
%"TAP"
"1","(-175,3000)","2","standard","I256";
;
CDS_LIB"standard"
BODY_TYPE"PLUMBING"
HDL_TAP"TRUE";
"B \NAC \NWC"8;
"S \NAC"
BN"15"9;
%"TAP"
"1","(3225,2350)","0","standard","I257";
;
CDS_LIB"standard"
BODY_TYPE"PLUMBING"
HDL_TAP"TRUE";
"B \NAC \NWC"6;
"S \NAC"
BN"2"54;
%"TAP"
"1","(3225,2300)","0","standard","I258";
;
CDS_LIB"standard"
BODY_TYPE"PLUMBING"
HDL_TAP"TRUE";
"B \NAC \NWC"6;
"S \NAC"
BN"1"55;
%"TAP"
"1","(3225,2250)","0","standard","I259";
;
CDS_LIB"standard"
BODY_TYPE"PLUMBING"
HDL_TAP"TRUE";
"B \NAC \NWC"6;
"S \NAC"
BN"0"56;
%"TAP"
"1","(-200,625)","2","standard","I26";
;
CDS_LIB"standard"
BODY_TYPE"PLUMBING"
HDL_TAP"TRUE";
"B \NAC \NWC"3;
"S \NAC"
BN"6"98;
%"TAP"
"1","(3225,2450)","0","standard","I260";
;
CDS_LIB"standard"
BODY_TYPE"PLUMBING"
HDL_TAP"TRUE";
"B \NAC \NWC"6;
"S \NAC"
BN"4"52;
%"TAP"
"1","(3225,2400)","0","standard","I261";
;
CDS_LIB"standard"
BODY_TYPE"PLUMBING"
HDL_TAP"TRUE";
"B \NAC \NWC"6;
"S \NAC"
BN"3"53;
%"TAP"
"1","(3225,2600)","0","standard","I262";
;
CDS_LIB"standard"
BODY_TYPE"PLUMBING"
HDL_TAP"TRUE";
"B \NAC \NWC"6;
"S \NAC"
BN"7"49;
%"TAP"
"1","(3225,2550)","0","standard","I263";
;
CDS_LIB"standard"
BODY_TYPE"PLUMBING"
HDL_TAP"TRUE";
"B \NAC \NWC"6;
"S \NAC"
BN"6"50;
%"TAP"
"1","(3225,2500)","0","standard","I264";
;
CDS_LIB"standard"
BODY_TYPE"PLUMBING"
HDL_TAP"TRUE";
"B \NAC \NWC"6;
"S \NAC"
BN"5"51;
%"TAP"
"1","(3225,2650)","0","standard","I265";
;
CDS_LIB"standard"
BODY_TYPE"PLUMBING"
HDL_TAP"TRUE";
"B \NAC \NWC"6;
"S \NAC"
BN"8"48;
%"TAP"
"1","(3225,2700)","0","standard","I266";
;
CDS_LIB"standard"
BODY_TYPE"PLUMBING"
HDL_TAP"TRUE";
"B \NAC \NWC"6;
"S \NAC"
BN"9"47;
%"TAP"
"1","(3225,2850)","0","standard","I267";
;
CDS_LIB"standard"
BODY_TYPE"PLUMBING"
HDL_TAP"TRUE";
"B \NAC \NWC"6;
"S \NAC"
BN"12"44;
%"TAP"
"1","(3225,2750)","0","standard","I268";
;
CDS_LIB"standard"
BODY_TYPE"PLUMBING"
HDL_TAP"TRUE";
"B \NAC \NWC"6;
"S \NAC"
BN"10"46;
%"TAP"
"1","(3225,2900)","0","standard","I269";
;
CDS_LIB"standard"
BODY_TYPE"PLUMBING"
HDL_TAP"TRUE";
"B \NAC \NWC"6;
"S \NAC"
BN"13"43;
%"TAP"
"1","(-200,725)","2","standard","I27";
;
CDS_LIB"standard"
BODY_TYPE"PLUMBING"
HDL_TAP"TRUE";
"B \NAC \NWC"3;
"S \NAC"
BN"8"96;
%"TAP"
"1","(3225,2950)","0","standard","I270";
;
CDS_LIB"standard"
BODY_TYPE"PLUMBING"
HDL_TAP"TRUE";
"B \NAC \NWC"6;
"S \NAC"
BN"14"42;
%"TAP"
"1","(3225,3000)","0","standard","I271";
;
CDS_LIB"standard"
BODY_TYPE"PLUMBING"
HDL_TAP"TRUE";
"B \NAC \NWC"6;
"S \NAC"
BN"15"41;
%"TAP"
"1","(3225,3100)","0","standard","I272";
;
CDS_LIB"standard"
BODY_TYPE"PLUMBING"
HDL_TAP"TRUE";
"B \NAC \NWC"5;
"S \NAC"
BN"0"72;
%"TAP"
"1","(3225,3250)","0","standard","I273";
;
CDS_LIB"standard"
BODY_TYPE"PLUMBING"
HDL_TAP"TRUE";
"B \NAC \NWC"5;
"S \NAC"
BN"3"69;
%"TAP"
"1","(3225,3150)","0","standard","I274";
;
CDS_LIB"standard"
BODY_TYPE"PLUMBING"
HDL_TAP"TRUE";
"B \NAC \NWC"5;
"S \NAC"
BN"1"71;
%"TAP"
"1","(3225,3200)","0","standard","I275";
;
CDS_LIB"standard"
BODY_TYPE"PLUMBING"
HDL_TAP"TRUE";
"B \NAC \NWC"5;
"S \NAC"
BN"2"70;
%"TAP"
"1","(3225,3350)","0","standard","I276";
;
CDS_LIB"standard"
BODY_TYPE"PLUMBING"
HDL_TAP"TRUE";
"B \NAC \NWC"5;
"S \NAC"
BN"5"67;
%"TAP"
"1","(3225,3300)","0","standard","I277";
;
CDS_LIB"standard"
BODY_TYPE"PLUMBING"
HDL_TAP"TRUE";
"B \NAC \NWC"5;
"S \NAC"
BN"4"68;
%"TAP"
"1","(3225,3500)","0","standard","I278";
;
CDS_LIB"standard"
BODY_TYPE"PLUMBING"
HDL_TAP"TRUE";
"B \NAC \NWC"5;
"S \NAC"
BN"8"64;
%"TAP"
"1","(3225,3400)","0","standard","I279";
;
CDS_LIB"standard"
BODY_TYPE"PLUMBING"
HDL_TAP"TRUE";
"B \NAC \NWC"5;
"S \NAC"
BN"6"66;
%"TAP"
"1","(-200,675)","2","standard","I28";
;
CDS_LIB"standard"
BODY_TYPE"PLUMBING"
HDL_TAP"TRUE";
"B \NAC \NWC"3;
"S \NAC"
BN"7"97;
%"TAP"
"1","(3225,3450)","0","standard","I280";
;
CDS_LIB"standard"
BODY_TYPE"PLUMBING"
HDL_TAP"TRUE";
"B \NAC \NWC"5;
"S \NAC"
BN"7"65;
%"TAP"
"1","(3225,3600)","0","standard","I281";
;
CDS_LIB"standard"
BODY_TYPE"PLUMBING"
HDL_TAP"TRUE";
"B \NAC \NWC"5;
"S \NAC"
BN"10"62;
%"TAP"
"1","(3225,3550)","0","standard","I282";
;
CDS_LIB"standard"
BODY_TYPE"PLUMBING"
HDL_TAP"TRUE";
"B \NAC \NWC"5;
"S \NAC"
BN"9"63;
%"TAP"
"1","(3225,3750)","0","standard","I283";
;
CDS_LIB"standard"
BODY_TYPE"PLUMBING"
HDL_TAP"TRUE";
"B \NAC \NWC"5;
"S \NAC"
BN"13"59;
%"TAP"
"1","(3225,3700)","0","standard","I284";
;
CDS_LIB"standard"
BODY_TYPE"PLUMBING"
HDL_TAP"TRUE";
"B \NAC \NWC"5;
"S \NAC"
BN"12"60;
%"TAP"
"1","(3225,3650)","0","standard","I285";
;
CDS_LIB"standard"
BODY_TYPE"PLUMBING"
HDL_TAP"TRUE";
"B \NAC \NWC"5;
"S \NAC"
BN"11"61;
%"TAP"
"1","(3225,3850)","0","standard","I286";
;
CDS_LIB"standard"
BODY_TYPE"PLUMBING"
HDL_TAP"TRUE";
"B \NAC \NWC"5;
"S \NAC"
BN"15"57;
%"TAP"
"1","(3225,3800)","0","standard","I287";
;
CDS_LIB"standard"
BODY_TYPE"PLUMBING"
HDL_TAP"TRUE";
"B \NAC \NWC"5;
"S \NAC"
BN"14"58;
%"TAP"
"1","(-200,775)","2","standard","I29";
;
CDS_LIB"standard"
BODY_TYPE"PLUMBING"
HDL_TAP"TRUE";
"B \NAC \NWC"3;
"S \NAC"
BN"9"95;
%"TAP"
"1","(3225,2800)","0","standard","I290";
;
CDS_LIB"standard"
BODY_TYPE"PLUMBING"
HDL_TAP"TRUE";
"B \NAC \NWC"6;
"S \NAC"
BN"11"45;
%"TAP"
"1","(-200,-425)","2","standard","I3";
;
CDS_LIB"standard"
BODY_TYPE"PLUMBING"
HDL_TAP"TRUE";
"B \NAC \NWC"4;
"S \NAC"
BN"2"86;
%"TAP"
"1","(-200,825)","2","standard","I30";
;
CDS_LIB"standard"
BODY_TYPE"PLUMBING"
HDL_TAP"TRUE";
"B \NAC \NWC"3;
"S \NAC"
BN"10"94;
%"TAP"
"1","(-200,875)","2","standard","I31";
;
CDS_LIB"standard"
BODY_TYPE"PLUMBING"
HDL_TAP"TRUE";
"B \NAC \NWC"3;
"S \NAC"
BN"11"93;
%"TAP"
"1","(-200,925)","2","standard","I32";
;
CDS_LIB"standard"
BODY_TYPE"PLUMBING"
HDL_TAP"TRUE";
"B \NAC \NWC"3;
"S \NAC"
BN"12"92;
%"TAP"
"1","(-200,975)","2","standard","I33";
;
CDS_LIB"standard"
BODY_TYPE"PLUMBING"
HDL_TAP"TRUE";
"B \NAC \NWC"3;
"S \NAC"
BN"13"91;
%"TAP"
"1","(-200,1025)","2","standard","I34";
;
CDS_LIB"standard"
BODY_TYPE"PLUMBING"
HDL_TAP"TRUE";
"B \NAC \NWC"3;
"S \NAC"
BN"14"90;
%"TAP"
"1","(-200,1075)","2","standard","I35";
;
CDS_LIB"standard"
BODY_TYPE"PLUMBING"
HDL_TAP"TRUE";
"B \NAC \NWC"3;
"S \NAC"
BN"15"89;
%"TAP"
"1","(-200,-375)","2","standard","I4";
;
CDS_LIB"standard"
BODY_TYPE"PLUMBING"
HDL_TAP"TRUE";
"B \NAC \NWC"4;
"S \NAC"
BN"3"85;
%"TAP"
"1","(-200,-275)","2","standard","I5";
;
CDS_LIB"standard"
BODY_TYPE"PLUMBING"
HDL_TAP"TRUE";
"B \NAC \NWC"4;
"S \NAC"
BN"5"83;
%"SOCKET4677_AZIF0045P001C01CS"
"19","(1500,3050)","0","pure_quanta","I54";
;
PART_NUMBER"DGA^7000023"
VALUE"SOCKET4677_AZIF0045-P001C01CS"
MATERIAL"IO"
PART_TYPE"SMLF"
$LOCATION"U1"
CDS_LMAN_SYM_OUTLINE"-1050,950,1050,-950"
NEEDS_NO_SIZE"TRUE"
CDS_LIB"pure_quanta"
CDS_LOCATION"U1"
$SEC"19"
CDS_SEC"19";
"PE2_TX_DP0"
$PN"CT14"72;
"PE2_TX_DP1"
$PN"CW15"71;
"PE2_TX_DP2"
$PN"CY14"70;
"PE2_TX_DP3"
$PN"DC15"69;
"PE2_TX_DP4"
$PN"DD14"68;
"PE2_TX_DP5"
$PN"DG15"67;
"PE2_TX_DP6"
$PN"DH14"66;
"PE2_TX_DP7"
$PN"DL15"65;
"PE2_TX_DP8"
$PN"DM14"64;
"PE2_TX_DP9"
$PN"DR15"63;
"PE2_TX_DP10"
$PN"DT14"62;
"PE2_TX_DP11"
$PN"DW15"61;
"PE2_TX_DP12"
$PN"DY14"60;
"PE2_TX_DP13"
$PN"EC15"59;
"PE2_TX_DP14"
$PN"ED14"58;
"PE2_TX_DP15"
$PN"EG15"57;
"PE2_TX_DN0"
$PN"CU13"56;
"PE2_TX_DN1"
$PN"CV14"55;
"PE2_TX_DN2"
$PN"DA13"54;
"PE2_TX_DN3"
$PN"DB14"53;
"PE2_TX_DN4"
$PN"DE13"52;
"PE2_TX_DN5"
$PN"DF14"51;
"PE2_TX_DN6"
$PN"DJ13"50;
"PE2_TX_DN7"
$PN"DK14"49;
"PE2_TX_DN8"
$PN"DN13"48;
"PE2_TX_DN9"
$PN"DP14"47;
"PE2_TX_DN10"
$PN"DU13"46;
"PE2_TX_DN11"
$PN"DV14"45;
"PE2_TX_DN12"
$PN"EA13"44;
"PE2_TX_DN13"
$PN"EB14"43;
"PE2_TX_DN14"
$PN"EE13"42;
"PE2_TX_DN15"
$PN"EF14"41;
"PE2_RX_DP0"
$PN"CV10"40;
"PE2_RX_DP1"
$PN"CW11"39;
"PE2_RX_DP2"
$PN"DB10"38;
"PE2_RX_DP3"
$PN"DC11"37;
"PE2_RX_DP4"
$PN"DF10"36;
"PE2_RX_DP5"
$PN"DG11"35;
"PE2_RX_DP6"
$PN"DK10"34;
"PE2_RX_DP7"
$PN"DL11"33;
"PE2_RX_DP8"
$PN"DP10"32;
"PE2_RX_DP9"
$PN"DR11"31;
"PE2_RX_DP10"
$PN"DV10"30;
"PE2_RX_DP11"
$PN"DW11"29;
"PE2_RX_DP12"
$PN"EB10"28;
"PE2_RX_DP13"
$PN"EC11"27;
"PE2_RX_DP14"
$PN"EF10"26;
"PE2_RX_DP15"
$PN"EG11"25;
"PE2_RX_DN0"
$PN"CU9"24;
"PE2_RX_DN1"
$PN"CY10"23;
"PE2_RX_DN2"
$PN"DA9"22;
"PE2_RX_DN3"
$PN"DD10"21;
"PE2_RX_DN4"
$PN"DE9"20;
"PE2_RX_DN5"
$PN"DH10"19;
"PE2_RX_DN6"
$PN"DJ9"18;
"PE2_RX_DN7"
$PN"DM10"17;
"PE2_RX_DN8"
$PN"DN9"16;
"PE2_RX_DN9"
$PN"DT10"15;
"PE2_RX_DN10"
$PN"DU9"14;
"PE2_RX_DN11"
$PN"DY10"13;
"PE2_RX_DN12"
$PN"EA9"12;
"PE2_RX_DN13"
$PN"ED10"11;
"PE2_RX_DN14"
$PN"EE9"10;
"PE2_RX_DN15"
$PN"EH10"9;
%"TAP"
"1","(-200,-325)","2","standard","I6";
;
CDS_LIB"standard"
BODY_TYPE"PLUMBING"
HDL_TAP"TRUE";
"B \NAC \NWC"4;
"S \NAC"
BN"4"84;
%"TAP"
"1","(-200,-225)","2","standard","I7";
;
CDS_LIB"standard"
BODY_TYPE"PLUMBING"
HDL_TAP"TRUE";
"B \NAC \NWC"4;
"S \NAC"
BN"6"82;
%"TAP"
"1","(3175,-525)","0","standard","I71";
;
CDS_LIB"standard"
BODY_TYPE"PLUMBING"
HDL_TAP"TRUE";
"B \NAC \NWC"2;
"S \NAC"
BN"0"120;
%"TAP"
"1","(3175,-475)","0","standard","I72";
;
CDS_LIB"standard"
BODY_TYPE"PLUMBING"
HDL_TAP"TRUE";
"B \NAC \NWC"2;
"S \NAC"
BN"1"119;
%"TAP"
"1","(3175,-425)","0","standard","I73";
;
CDS_LIB"standard"
BODY_TYPE"PLUMBING"
HDL_TAP"TRUE";
"B \NAC \NWC"2;
"S \NAC"
BN"2"118;
%"TAP"
"1","(3175,-375)","0","standard","I74";
;
CDS_LIB"standard"
BODY_TYPE"PLUMBING"
HDL_TAP"TRUE";
"B \NAC \NWC"2;
"S \NAC"
BN"3"117;
%"TAP"
"1","(3175,-325)","0","standard","I75";
;
CDS_LIB"standard"
BODY_TYPE"PLUMBING"
HDL_TAP"TRUE";
"B \NAC \NWC"2;
"S \NAC"
BN"4"116;
%"TAP"
"1","(3175,-275)","0","standard","I76";
;
CDS_LIB"standard"
BODY_TYPE"PLUMBING"
HDL_TAP"TRUE";
"B \NAC \NWC"2;
"S \NAC"
BN"5"115;
%"TAP"
"1","(3175,-225)","0","standard","I77";
;
CDS_LIB"standard"
BODY_TYPE"PLUMBING"
HDL_TAP"TRUE";
"B \NAC \NWC"2;
"S \NAC"
BN"6"114;
%"TAP"
"1","(3175,-175)","0","standard","I78";
;
CDS_LIB"standard"
BODY_TYPE"PLUMBING"
HDL_TAP"TRUE";
"B \NAC \NWC"2;
"S \NAC"
BN"7"113;
%"TAP"
"1","(3175,-125)","0","standard","I79";
;
CDS_LIB"standard"
BODY_TYPE"PLUMBING"
HDL_TAP"TRUE";
"B \NAC \NWC"2;
"S \NAC"
BN"8"112;
%"TAP"
"1","(-200,-175)","2","standard","I8";
;
CDS_LIB"standard"
BODY_TYPE"PLUMBING"
HDL_TAP"TRUE";
"B \NAC \NWC"4;
"S \NAC"
BN"7"81;
%"TAP"
"1","(3175,-25)","0","standard","I80";
;
CDS_LIB"standard"
BODY_TYPE"PLUMBING"
HDL_TAP"TRUE";
"B \NAC \NWC"2;
"S \NAC"
BN"10"110;
%"TAP"
"1","(3175,-75)","0","standard","I81";
;
CDS_LIB"standard"
BODY_TYPE"PLUMBING"
HDL_TAP"TRUE";
"B \NAC \NWC"2;
"S \NAC"
BN"9"111;
%"TAP"
"1","(3175,25)","0","standard","I82";
;
CDS_LIB"standard"
BODY_TYPE"PLUMBING"
HDL_TAP"TRUE";
"B \NAC \NWC"2;
"S \NAC"
BN"11"109;
%"TAP"
"1","(3175,75)","0","standard","I83";
;
CDS_LIB"standard"
BODY_TYPE"PLUMBING"
HDL_TAP"TRUE";
"B \NAC \NWC"2;
"S \NAC"
BN"12"108;
%"TAP"
"1","(3175,125)","0","standard","I84";
;
CDS_LIB"standard"
BODY_TYPE"PLUMBING"
HDL_TAP"TRUE";
"B \NAC \NWC"2;
"S \NAC"
BN"13"107;
%"TAP"
"1","(3175,175)","0","standard","I85";
;
CDS_LIB"standard"
BODY_TYPE"PLUMBING"
HDL_TAP"TRUE";
"B \NAC \NWC"2;
"S \NAC"
BN"14"106;
%"TAP"
"1","(3175,225)","0","standard","I86";
;
CDS_LIB"standard"
BODY_TYPE"PLUMBING"
HDL_TAP"TRUE";
"B \NAC \NWC"2;
"S \NAC"
BN"15"105;
%"TAP"
"1","(3175,325)","0","standard","I87";
;
CDS_LIB"standard"
BODY_TYPE"PLUMBING"
HDL_TAP"TRUE";
"B \NAC \NWC"1;
"S \NAC"
BN"0"136;
%"TAP"
"1","(3175,375)","0","standard","I88";
;
CDS_LIB"standard"
BODY_TYPE"PLUMBING"
HDL_TAP"TRUE";
"B \NAC \NWC"1;
"S \NAC"
BN"1"135;
%"TAP"
"1","(3175,475)","0","standard","I89";
;
CDS_LIB"standard"
BODY_TYPE"PLUMBING"
HDL_TAP"TRUE";
"B \NAC \NWC"1;
"S \NAC"
BN"3"133;
%"TAP"
"1","(-200,-75)","2","standard","I9";
;
CDS_LIB"standard"
BODY_TYPE"PLUMBING"
HDL_TAP"TRUE";
"B \NAC \NWC"4;
"S \NAC"
BN"9"79;
%"TAP"
"1","(3175,525)","0","standard","I90";
;
CDS_LIB"standard"
BODY_TYPE"PLUMBING"
HDL_TAP"TRUE";
"B \NAC \NWC"1;
"S \NAC"
BN"4"132;
%"TAP"
"1","(3175,425)","0","standard","I91";
;
CDS_LIB"standard"
BODY_TYPE"PLUMBING"
HDL_TAP"TRUE";
"B \NAC \NWC"1;
"S \NAC"
BN"2"134;
%"TAP"
"1","(3175,575)","0","standard","I92";
;
CDS_LIB"standard"
BODY_TYPE"PLUMBING"
HDL_TAP"TRUE";
"B \NAC \NWC"1;
"S \NAC"
BN"5"131;
%"TAP"
"1","(3175,625)","0","standard","I93";
;
CDS_LIB"standard"
BODY_TYPE"PLUMBING"
HDL_TAP"TRUE";
"B \NAC \NWC"1;
"S \NAC"
BN"6"130;
%"TAP"
"1","(3175,675)","0","standard","I94";
;
CDS_LIB"standard"
BODY_TYPE"PLUMBING"
HDL_TAP"TRUE";
"B \NAC \NWC"1;
"S \NAC"
BN"7"129;
%"TAP"
"1","(3175,725)","0","standard","I95";
;
CDS_LIB"standard"
BODY_TYPE"PLUMBING"
HDL_TAP"TRUE";
"B \NAC \NWC"1;
"S \NAC"
BN"8"128;
%"TAP"
"1","(3175,775)","0","standard","I96";
;
CDS_LIB"standard"
BODY_TYPE"PLUMBING"
HDL_TAP"TRUE";
"B \NAC \NWC"1;
"S \NAC"
BN"9"127;
%"TAP"
"1","(3175,825)","0","standard","I97";
;
CDS_LIB"standard"
BODY_TYPE"PLUMBING"
HDL_TAP"TRUE";
"B \NAC \NWC"1;
"S \NAC"
BN"10"126;
%"TAP"
"1","(3175,875)","0","standard","I98";
;
CDS_LIB"standard"
BODY_TYPE"PLUMBING"
HDL_TAP"TRUE";
"B \NAC \NWC"1;
"S \NAC"
BN"11"125;
%"TAP"
"1","(3175,975)","0","standard","I99";
;
CDS_LIB"standard"
BODY_TYPE"PLUMBING"
HDL_TAP"TRUE";
"B \NAC \NWC"1;
"S \NAC"
BN"13"123;
END.
